(kicad_pcb
	(version 20260206)
	(generator "pcbnew")
	(generator_version "10.0")
	(general
		(thickness 1.6)
		(legacy_teardrops no)
	)
	(paper "A4")
	(title_block
		(title "peb — Lightning_PEB_BRD.brd")
		(comment 1 "Lightning (Wiwynn / Facebook NVMe JBOF) / footprints 2045-2052 of 2563")
	)
	(layers
		(0 "F.Cu" signal "TOP")
		(4 "In1.Cu" signal "L2GND")
		(6 "In2.Cu" signal "L3")
		(8 "In3.Cu" signal "L4VCC")
		(10 "In4.Cu" signal "L5VCC")
		(12 "In5.Cu" signal "L6")
		(14 "In6.Cu" signal "L7GND")
		(2 "B.Cu" signal "BOTTOM")
		(9 "F.Adhes" user "F.Adhesive")
		(11 "B.Adhes" user "B.Adhesive")
		(13 "F.Paste" user "Package Geometry/Pastemask Top")
		(15 "B.Paste" user "Package Geometry/Pastemask Bottom")
		(5 "F.SilkS" user "Ref Des/Silkscreen Top")
		(7 "B.SilkS" user "Ref Des/Silkscreen Bottom")
		(1 "F.Mask" user "Board Geometry/Soldermask Top")
		(3 "B.Mask" user "Board Geometry/Soldermask Bottom")
		(17 "Dwgs.User" user "User.Drawings")
		(19 "Cmts.User" user "User.Comments")
		(21 "Eco1.User" user "User.Eco1")
		(23 "Eco2.User" user "User.Eco2")
		(25 "Edge.Cuts" user "Board Geometry/Outline")
		(27 "Margin" user)
		(31 "F.CrtYd" user "Package Geometry/Place Bound Top")
		(29 "B.CrtYd" user "Package Geometry/Place Bound Bottom")
		(35 "F.Fab" user "Ref Des/Assembly Top")
		(33 "B.Fab" user "Ref Des/Assembly Bottom")
	)
	(footprint ""
		(layer "B.Cu")
		(at 137.8712 -205.9432)
		(property "Reference" "R9035"
			(at 0 0 0)
			(layer "B.SilkS")
			(hide yes)
			(effects
				(font
					(size 1.27 1.27)
				)
				(justify mirror)
			)
		)
		(property "Value" "4K7R2F-GP"
			(at -0.064008 -3.993896 0)
			(unlocked yes)
			(layer "B.Fab")
			(hide yes)
			(effects
				(font
					(size 1.016 1.016)
					(thickness 0.1524)
				)
				(justify mirror)
			)
		)
		(property "Device Type" "R402H16"
			(at -0.064008 -5.517896 0)
			(unlocked yes)
			(layer "B.Fab")
			(hide yes)
			(effects
				(font
					(size 1.016 1.016)
					(thickness 0.1524)
				)
				(justify mirror)
			)
		)
		(duplicate_pad_numbers_are_jumpers no)
		(fp_line
			(start -0.508 -0.9398)
			(end 0.508 -0.9398)
			(stroke
				(width 0.1524)
				(type default)
			)
			(layer "B.SilkS")
		)
		(fp_line
			(start 0.508 -0.9398)
			(end 0.508 0.9398)
			(stroke
				(width 0.1524)
				(type default)
			)
			(layer "B.SilkS")
		)
		(fp_rect
			(start 0.508 0.9398)
			(end -0.508 -0.9398)
			(stroke
				(width 0)
				(type default)
			)
			(fill no)
			(layer "B.CrtYd")
		)
		(fp_rect
			(start 0.508 0.9398)
			(end -0.508 -0.9398)
			(stroke
				(width 0)
				(type default)
			)
			(fill no)
			(layer "B.Fab")
		)
		(pad "1" smd custom
			(at 0 -0.4445 180)
			(size 0.1397 0.1397)
			(layers "B.Cu" "B.Mask" "B.Paste")
			(net "SSD_PERST#6")
			(options
				(clearance outline)
				(anchor circle)
			)
			(primitives
				(gr_poly
					(pts
						(arc
							(start -0.1778 0.2794)
							(mid -0.249642 0.249642)
							(end -0.2794 0.1778)
						)
						(arc
							(start -0.2794 -0.1778)
							(mid -0.249642 -0.249642)
							(end -0.1778 -0.2794)
						)
						(arc
							(start 0.1778 -0.2794)
							(mid 0.249642 -0.249642)
							(end 0.2794 -0.1778)
						)
						(arc
							(start 0.2794 0.1778)
							(mid 0.249642 0.249642)
							(end 0.1778 0.2794)
						)
					)
					(width 0)
					(fill yes)
				)
			)
		)
		(pad "2" smd custom
			(at 0 0.4445 180)
			(size 0.1397 0.1397)
			(layers "B.Cu" "B.Mask" "B.Paste")
			(net "GND")
			(options
				(clearance outline)
				(anchor circle)
			)
			(primitives
				(gr_poly
					(pts
						(arc
							(start -0.1778 0.2794)
							(mid -0.249642 0.249642)
							(end -0.2794 0.1778)
						)
						(arc
							(start -0.2794 -0.1778)
							(mid -0.249642 -0.249642)
							(end -0.1778 -0.2794)
						)
						(arc
							(start 0.1778 -0.2794)
							(mid 0.249642 -0.249642)
							(end 0.2794 -0.1778)
						)
						(arc
							(start 0.2794 0.1778)
							(mid 0.249642 0.249642)
							(end 0.1778 0.2794)
						)
					)
					(width 0)
					(fill yes)
				)
			)
		)
	)
	(footprint ""
		(layer "B.Cu")
		(at 53.222652 -108.06303 90)
		(property "Reference" "R52"
			(at 0 0 90)
			(layer "B.SilkS")
			(hide yes)
			(effects
				(font
					(size 1.27 1.27)
				)
				(justify mirror)
			)
		)
		(property "Value" "0R2J-2-GP"
			(at -0.064008 -3.993896 90)
			(unlocked yes)
			(layer "B.Fab")
			(hide yes)
			(effects
				(font
					(size 1.016 1.016)
					(thickness 0.1524)
				)
				(justify mirror)
			)
		)
		(property "Device Type" "R402H16"
			(at -0.064008 -5.517896 90)
			(unlocked yes)
			(layer "B.Fab")
			(hide yes)
			(effects
				(font
					(size 1.016 1.016)
					(thickness 0.1524)
				)
				(justify mirror)
			)
		)
		(duplicate_pad_numbers_are_jumpers no)
		(fp_line
			(start 0.508 -0.9398)
			(end 0.508 0.9398)
			(stroke
				(width 0.1524)
				(type default)
			)
			(layer "B.SilkS")
		)
		(fp_line
			(start -0.508 -0.9398)
			(end 0.508 -0.9398)
			(stroke
				(width 0.1524)
				(type default)
			)
			(layer "B.SilkS")
		)
		(fp_rect
			(start 0.508 0.9398)
			(end -0.508 -0.9398)
			(stroke
				(width 0)
				(type default)
			)
			(fill no)
			(layer "B.CrtYd")
		)
		(fp_rect
			(start 0.508 0.9398)
			(end -0.508 -0.9398)
			(stroke
				(width 0)
				(type default)
			)
			(fill no)
			(layer "B.Fab")
		)
		(pad "1" smd custom
			(at 0 -0.4445 270)
			(size 0.1397 0.1397)
			(layers "B.Cu" "B.Mask" "B.Paste")
			(net "BMC_I2C12_MINI6_SCL_S")
			(options
				(clearance outline)
				(anchor circle)
			)
			(primitives
				(gr_poly
					(pts
						(arc
							(start -0.1778 0.2794)
							(mid -0.249642 0.249642)
							(end -0.2794 0.1778)
						)
						(arc
							(start -0.2794 -0.1778)
							(mid -0.249642 -0.249642)
							(end -0.1778 -0.2794)
						)
						(arc
							(start 0.1778 -0.2794)
							(mid 0.249642 -0.249642)
							(end 0.2794 -0.1778)
						)
						(arc
							(start 0.2794 0.1778)
							(mid 0.249642 0.249642)
							(end 0.1778 0.2794)
						)
					)
					(width 0)
					(fill yes)
				)
			)
		)
		(pad "2" smd custom
			(at 0 0.4445 270)
			(size 0.1397 0.1397)
			(layers "B.Cu" "B.Mask" "B.Paste")
			(net "BMC_I2C12_MINI6_SCL")
			(options
				(clearance outline)
				(anchor circle)
			)
			(primitives
				(gr_poly
					(pts
						(arc
							(start -0.1778 0.2794)
							(mid -0.249642 0.249642)
							(end -0.2794 0.1778)
						)
						(arc
							(start -0.2794 -0.1778)
							(mid -0.249642 -0.249642)
							(end -0.1778 -0.2794)
						)
						(arc
							(start 0.1778 -0.2794)
							(mid 0.249642 -0.249642)
							(end 0.2794 -0.1778)
						)
						(arc
							(start 0.2794 0.1778)
							(mid 0.249642 0.249642)
							(end 0.1778 0.2794)
						)
					)
					(width 0)
					(fill yes)
				)
			)
		)
	)
	(footprint ""
		(layer "B.Cu")
		(at 29.913834 -126.973584)
		(property "Reference" "TP221"
			(at 0 0 0)
			(layer "B.SilkS")
			(hide yes)
			(effects
				(font
					(size 1.27 1.27)
				)
				(justify mirror)
			)
		)
		(property "Value" "TPAD28-2-GP"
			(at 0.0127 -1.6637 0)
			(unlocked yes)
			(layer "B.Fab")
			(hide yes)
			(effects
				(font
					(size 1.016 1.016)
					(thickness 0.1524)
				)
				(justify mirror)
			)
		)
		(property "Device Type" "TPAD28"
			(at 0.0127 -3.1877 0)
			(unlocked yes)
			(layer "B.Fab")
			(hide yes)
			(effects
				(font
					(size 1.016 1.016)
					(thickness 0.1524)
				)
				(justify mirror)
			)
		)
		(duplicate_pad_numbers_are_jumpers no)
		(fp_poly
			(pts
				(arc
					(start 0.3556 0)
					(mid -0.3556 0)
					(end 0.3556 0)
				)
			)
			(stroke
				(width 0)
				(type default)
			)
			(fill no)
			(layer "B.CrtYd")
		)
		(fp_poly
			(pts
				(arc
					(start 0.6096 0)
					(mid -0.6096 0)
					(end 0.6096 0)
				)
			)
			(stroke
				(width 0)
				(type default)
			)
			(fill no)
			(layer "B.Fab")
		)
		(pad "1" smd circle
			(at 0 0 180)
			(size 0.7112 0.7112)
			(layers "B.Cu" "B.Mask" "B.Paste")
			(net "TP_GPIOB6")
		)
	)
	(footprint ""
		(layer "B.Cu")
		(at 73.705212 -186.545474)
		(property "Reference" "C3201"
			(at 0 0 0)
			(layer "B.SilkS")
			(hide yes)
			(effects
				(font
					(size 1.27 1.27)
				)
				(justify mirror)
			)
		)
		(property "Value" "SCD1U25V2KX-2-GP"
			(at -1.1811 -2.7051 0)
			(unlocked yes)
			(layer "B.Fab")
			(hide yes)
			(effects
				(font
					(size 1.016 1.016)
					(thickness 0.1524)
				)
				(justify mirror)
			)
		)
		(property "Device Type" "C402H22"
			(at -1.1811 -4.2291 0)
			(unlocked yes)
			(layer "B.Fab")
			(hide yes)
			(effects
				(font
					(size 1.016 1.016)
					(thickness 0.1524)
				)
				(justify mirror)
			)
		)
		(duplicate_pad_numbers_are_jumpers no)
		(fp_rect
			(start 0.4318 0.9525)
			(end -0.4318 -0.9525)
			(stroke
				(width 0)
				(type default)
			)
			(fill no)
			(layer "B.CrtYd")
		)
		(fp_rect
			(start 0.4318 0.9525)
			(end -0.4318 -0.9525)
			(stroke
				(width 0)
				(type default)
			)
			(fill no)
			(layer "B.Fab")
		)
		(pad "1" smd custom
			(at 0 -0.4445 180)
			(size 0.1524 0.1524)
			(layers "B.Cu" "B.Mask" "B.Paste")
			(net "P3V3_STBY")
			(options
				(clearance outline)
				(anchor circle)
			)
			(primitives
				(gr_poly
					(pts
						(arc
							(start 0.3048 0.2032)
							(mid 0.275042 0.275042)
							(end 0.2032 0.3048)
						)
						(arc
							(start -0.2032 0.3048)
							(mid -0.275042 0.275042)
							(end -0.3048 0.2032)
						)
						(arc
							(start -0.3048 -0.2032)
							(mid -0.275042 -0.275042)
							(end -0.2032 -0.3048)
						)
						(arc
							(start 0.2032 -0.3048)
							(mid 0.275042 -0.275042)
							(end 0.3048 -0.2032)
						)
					)
					(width 0)
					(fill yes)
				)
			)
		)
		(pad "2" smd custom
			(at 0 0.4445 180)
			(size 0.1524 0.1524)
			(layers "B.Cu" "B.Mask" "B.Paste")
			(net "GND")
			(options
				(clearance outline)
				(anchor circle)
			)
			(primitives
				(gr_poly
					(pts
						(arc
							(start 0.3048 0.2032)
							(mid 0.275042 0.275042)
							(end 0.2032 0.3048)
						)
						(arc
							(start -0.2032 0.3048)
							(mid -0.275042 0.275042)
							(end -0.3048 0.2032)
						)
						(arc
							(start -0.3048 -0.2032)
							(mid -0.275042 -0.275042)
							(end -0.2032 -0.3048)
						)
						(arc
							(start 0.2032 -0.3048)
							(mid 0.275042 -0.275042)
							(end 0.3048 -0.2032)
						)
					)
					(width 0)
					(fill yes)
				)
			)
		)
	)
	(footprint ""
		(layer "B.Cu")
		(at 229.9208 -47.0408 90)
		(property "Reference" "C491"
			(at 0 0 90)
			(layer "B.SilkS")
			(hide yes)
			(effects
				(font
					(size 1.27 1.27)
				)
				(justify mirror)
			)
		)
		(property "Value" "SCD1U16V1KX-1-GP"
			(at 2.8321 -1.7399 90)
			(unlocked yes)
			(layer "B.Fab")
			(hide yes)
			(effects
				(font
					(size 1.016 1.016)
					(thickness 0.1524)
				)
				(justify mirror)
			)
		)
		(property "Device Type" "C0201H13"
			(at 2.8321 -3.2639 90)
			(unlocked yes)
			(layer "B.Fab")
			(hide yes)
			(effects
				(font
					(size 1.016 1.016)
					(thickness 0.1524)
				)
				(justify mirror)
			)
		)
		(duplicate_pad_numbers_are_jumpers no)
		(fp_rect
			(start 0.2794 0.6477)
			(end -0.2794 -0.6477)
			(stroke
				(width 0)
				(type default)
			)
			(fill no)
			(layer "B.CrtYd")
		)
		(fp_rect
			(start 0.2794 0.6477)
			(end -0.2794 -0.6477)
			(stroke
				(width 0)
				(type default)
			)
			(fill no)
			(layer "B.Fab")
		)
		(pad "1" smd custom
			(at 0 -0.2794 270)
			(size 0.0762 0.0762)
			(layers "B.Cu" "B.Mask" "B.Paste")
			(net "DUT_AVD_PCIE")
			(options
				(clearance outline)
				(anchor circle)
			)
			(primitives
				(gr_poly
					(pts
						(arc
							(start 0.1524 0.127)
							(mid 0.137521 0.162921)
							(end 0.1016 0.1778)
						)
						(arc
							(start -0.1016 0.1778)
							(mid -0.137521 0.162921)
							(end -0.1524 0.127)
						)
						(arc
							(start -0.1524 -0.127)
							(mid -0.137521 -0.162921)
							(end -0.1016 -0.1778)
						)
						(arc
							(start 0.1016 -0.1778)
							(mid 0.137521 -0.162921)
							(end 0.1524 -0.127)
						)
					)
					(width 0)
					(fill yes)
				)
			)
		)
		(pad "2" smd custom
			(at 0 0.2794 270)
			(size 0.0762 0.0762)
			(layers "B.Cu" "B.Mask" "B.Paste")
			(net "GND")
			(options
				(clearance outline)
				(anchor circle)
			)
			(primitives
				(gr_poly
					(pts
						(arc
							(start 0.1524 0.127)
							(mid 0.137521 0.162921)
							(end 0.1016 0.1778)
						)
						(arc
							(start -0.1016 0.1778)
							(mid -0.137521 0.162921)
							(end -0.1524 0.127)
						)
						(arc
							(start -0.1524 -0.127)
							(mid -0.137521 -0.162921)
							(end -0.1016 -0.1778)
						)
						(arc
							(start 0.1016 -0.1778)
							(mid 0.137521 -0.162921)
							(end 0.1524 -0.127)
						)
					)
					(width 0)
					(fill yes)
				)
			)
		)
	)
	(footprint ""
		(layer "B.Cu")
		(at 327.533 -70.104 180)
		(property "Reference" "PC186"
			(at 0 0 0)
			(layer "B.SilkS")
			(hide yes)
			(effects
				(font
					(size 1.27 1.27)
				)
				(justify mirror)
			)
		)
		(property "Value" "SCD1U16V2KX-3GP"
			(at -1.1811 -2.7051 180)
			(unlocked yes)
			(layer "B.Fab")
			(hide yes)
			(effects
				(font
					(size 1.016 1.016)
					(thickness 0.1524)
				)
				(justify mirror)
			)
		)
		(property "Device Type" "C402H22"
			(at -1.1811 -4.2291 180)
			(unlocked yes)
			(layer "B.Fab")
			(hide yes)
			(effects
				(font
					(size 1.016 1.016)
					(thickness 0.1524)
				)
				(justify mirror)
			)
		)
		(duplicate_pad_numbers_are_jumpers no)
		(fp_rect
			(start 0.4318 0.9525)
			(end -0.4318 -0.9525)
			(stroke
				(width 0)
				(type default)
			)
			(fill no)
			(layer "B.CrtYd")
		)
		(fp_rect
			(start 0.4318 0.9525)
			(end -0.4318 -0.9525)
			(stroke
				(width 0)
				(type default)
			)
			(fill no)
			(layer "B.Fab")
		)
		(pad "1" smd custom
			(at 0 -0.4445)
			(size 0.1524 0.1524)
			(layers "B.Cu" "B.Mask" "B.Paste")
			(net "P0V9_E")
			(options
				(clearance outline)
				(anchor circle)
			)
			(primitives
				(gr_poly
					(pts
						(arc
							(start 0.3048 0.2032)
							(mid 0.275042 0.275042)
							(end 0.2032 0.3048)
						)
						(arc
							(start -0.2032 0.3048)
							(mid -0.275042 0.275042)
							(end -0.3048 0.2032)
						)
						(arc
							(start -0.3048 -0.2032)
							(mid -0.275042 -0.275042)
							(end -0.2032 -0.3048)
						)
						(arc
							(start 0.2032 -0.3048)
							(mid 0.275042 -0.275042)
							(end 0.3048 -0.2032)
						)
					)
					(width 0)
					(fill yes)
				)
			)
		)
		(pad "2" smd custom
			(at 0 0.4445)
			(size 0.1524 0.1524)
			(layers "B.Cu" "B.Mask" "B.Paste")
			(net "P0V9_E_SW_R")
			(options
				(clearance outline)
				(anchor circle)
			)
			(primitives
				(gr_poly
					(pts
						(arc
							(start 0.3048 0.2032)
							(mid 0.275042 0.275042)
							(end 0.2032 0.3048)
						)
						(arc
							(start -0.2032 0.3048)
							(mid -0.275042 0.275042)
							(end -0.3048 0.2032)
						)
						(arc
							(start -0.3048 -0.2032)
							(mid -0.275042 -0.275042)
							(end -0.2032 -0.3048)
						)
						(arc
							(start 0.2032 -0.3048)
							(mid 0.275042 -0.275042)
							(end 0.3048 -0.2032)
						)
					)
					(width 0)
					(fill yes)
				)
			)
		)
	)
	(footprint ""
		(layer "B.Cu")
		(at 238.9124 -56.9976 -90)
		(property "Reference" "C531"
			(at 0 0 90)
			(layer "B.SilkS")
			(hide yes)
			(effects
				(font
					(size 1.27 1.27)
				)
				(justify mirror)
			)
		)
		(property "Value" "SCD1U16V1KX-1-GP"
			(at 2.8321 -1.7399 270)
			(unlocked yes)
			(layer "B.Fab")
			(hide yes)
			(effects
				(font
					(size 1.016 1.016)
					(thickness 0.1524)
				)
				(justify mirror)
			)
		)
		(property "Device Type" "C0201H13"
			(at 2.8321 -3.2639 270)
			(unlocked yes)
			(layer "B.Fab")
			(hide yes)
			(effects
				(font
					(size 1.016 1.016)
					(thickness 0.1524)
				)
				(justify mirror)
			)
		)
		(duplicate_pad_numbers_are_jumpers no)
		(fp_rect
			(start 0.2794 0.6477)
			(end -0.2794 -0.6477)
			(stroke
				(width 0)
				(type default)
			)
			(fill no)
			(layer "B.CrtYd")
		)
		(fp_rect
			(start 0.2794 0.6477)
			(end -0.2794 -0.6477)
			(stroke
				(width 0)
				(type default)
			)
			(fill no)
			(layer "B.Fab")
		)
		(pad "1" smd custom
			(at 0 -0.2794 90)
			(size 0.0762 0.0762)
			(layers "B.Cu" "B.Mask" "B.Paste")
			(net "DUT_AVD_TX")
			(options
				(clearance outline)
				(anchor circle)
			)
			(primitives
				(gr_poly
					(pts
						(arc
							(start 0.1524 0.127)
							(mid 0.137521 0.162921)
							(end 0.1016 0.1778)
						)
						(arc
							(start -0.1016 0.1778)
							(mid -0.137521 0.162921)
							(end -0.1524 0.127)
						)
						(arc
							(start -0.1524 -0.127)
							(mid -0.137521 -0.162921)
							(end -0.1016 -0.1778)
						)
						(arc
							(start 0.1016 -0.1778)
							(mid 0.137521 -0.162921)
							(end 0.1524 -0.127)
						)
					)
					(width 0)
					(fill yes)
				)
			)
		)
		(pad "2" smd custom
			(at 0 0.2794 90)
			(size 0.0762 0.0762)
			(layers "B.Cu" "B.Mask" "B.Paste")
			(net "GND")
			(options
				(clearance outline)
				(anchor circle)
			)
			(primitives
				(gr_poly
					(pts
						(arc
							(start 0.1524 0.127)
							(mid 0.137521 0.162921)
							(end 0.1016 0.1778)
						)
						(arc
							(start -0.1016 0.1778)
							(mid -0.137521 0.162921)
							(end -0.1524 0.127)
						)
						(arc
							(start -0.1524 -0.127)
							(mid -0.137521 -0.162921)
							(end -0.1016 -0.1778)
						)
						(arc
							(start 0.1016 -0.1778)
							(mid 0.137521 -0.162921)
							(end 0.1524 -0.127)
						)
					)
					(width 0)
					(fill yes)
				)
			)
		)
	)
	(footprint ""
		(layer "B.Cu")
		(at 223.393 -196.977)
		(property "Reference" "U72"
			(at 0 0 0)
			(layer "B.SilkS")
			(hide yes)
			(effects
				(font
					(size 1.27 1.27)
				)
				(justify mirror)
			)
		)
		(property "Value" "SN74LVC1G08DCKR-GP"
			(at 2.3368 -8.6868 0)
			(unlocked yes)
			(layer "B.Fab")
			(hide yes)
			(effects
				(font
					(size 1.016 1.016)
					(thickness 0.1524)
				)
				(justify mirror)
			)
		)
		(property "Device Type" "SC70-5H44"
			(at 2.3114 -10.414 0)
			(unlocked yes)
			(layer "B.Fab")
			(hide yes)
			(effects
				(font
					(size 1.016 1.016)
					(thickness 0.1524)
				)
				(justify mirror)
			)
		)
		(duplicate_pad_numbers_are_jumpers no)
		(fp_line
			(start -1.3843 -1.8034)
			(end -1.3843 -1.1176)
			(stroke
				(width 0.3302)
				(type default)
			)
			(layer "B.SilkS")
		)
		(fp_line
			(start -1.27 -1.7018)
			(end -1.27 1.7018)
			(stroke
				(width 0.1524)
				(type default)
			)
			(layer "B.SilkS")
		)
		(fp_line
			(start -1.27 1.7018)
			(end 1.27 1.7018)
			(stroke
				(width 0.1524)
				(type default)
			)
			(layer "B.SilkS")
		)
		(fp_line
			(start -0.6604 -1.8034)
			(end -1.3843 -1.8034)
			(stroke
				(width 0.3302)
				(type default)
			)
			(layer "B.SilkS")
		)
		(fp_line
			(start 1.27 -1.7018)
			(end -1.27 -1.7018)
			(stroke
				(width 0.1524)
				(type default)
			)
			(layer "B.SilkS")
		)
		(fp_line
			(start 1.27 1.7018)
			(end 1.27 -1.7018)
			(stroke
				(width 0.1524)
				(type default)
			)
			(layer "B.SilkS")
		)
		(fp_rect
			(start 1.524 1.9558)
			(end -1.524 -1.9558)
			(stroke
				(width 0)
				(type default)
			)
			(fill no)
			(layer "B.CrtYd")
		)
		(fp_poly
			(pts
				(xy 1.524 -1.9558) (xy -1.524 -1.9558) (xy -1.524 1.9558) (xy 1.524 1.9558)
			)
			(stroke
				(width 0)
				(type default)
			)
			(fill no)
			(layer "B.Fab")
		)
		(pad "1" smd rect
			(at -0.65024 -0.8255 180)
			(size 0.4064 1.2192)
			(layers "B.Cu" "B.Mask" "B.Paste")
			(net "BMC_SSD_RST#0_A8")
		)
		(pad "2" smd rect
			(at 0 -0.8255 180)
			(size 0.4064 1.2192)
			(layers "B.Cu" "B.Mask" "B.Paste")
			(net "SSD_PERST#0_B8")
		)
		(pad "3" smd rect
			(at 0.65024 -0.8255 180)
			(size 0.4064 1.2192)
			(layers "B.Cu" "B.Mask" "B.Paste")
			(net "GND")
		)
		(pad "4" smd rect
			(at 0.65024 0.8255 180)
			(size 0.4064 1.2192)
			(layers "B.Cu" "B.Mask" "B.Paste")
			(net "SSD_PERST_Y8")
		)
		(pad "5" smd rect
			(at -0.65024 0.8255 180)
			(size 0.4064 1.2192)
			(layers "B.Cu" "B.Mask" "B.Paste")
			(net "P3V3_STBY")
		)
	)
)
